FILE_TYPE = CONNECTIVITY;
{Allegro Design Entry HDL 17.2-2016 S081 (4005846) 1/11/2022}
"PAGE_NUMBER" = 192;
0"NC";
1"P3V3_STBY\g";
2"P3V3_STBY\g";
3"GND\g";
4"GND\g";
5"GND\g";
6"GND\g";
7"GND\g";
8"GND\g";
9"GND\g";
10"P5V_STBY\g";
11"GND\g";
12"GND\g";
13"GND\g";
14"GND\g";
15"GND\g";
16"GND\g";
17"GND\g";
18"GND\g";
19"GND\g";
20"GND\g";
21"VSENSE_VSS_SENSE_B_P1";
22"VSENSE_PVDDIO_P1_DP";
23"PVDDIO_P1\g";
24"VSENSE_VSS_SENSE_C_P1";
25"VSENSE_PVDDCR_CPU1_P1_DP";
26"PVDDCR_CPU1_P1\g";
27"P3V3_STBY\g";
28"PVDDIO_P1_PWM2";
29"PVDDIO_P1_IMON2";
30"PVDDCR_CPU1_P1_PWM6";
31"PVDDCR_CPU1_P1_PWM5";
32"PVDDCR_CPU1_P1_IMON4";
33"PVDDCR_CPU1_P1_IMON2";
34"PVDDCR_CPU1_P1_IMON1";
35"PVDDCR_CPU1_P1_PWM1";
36"PVDDIO_P1_IMON1";
37"PVDDIO_P1_PWM1";
38"PVDDIO_P1_IMON3";
39"PVDDCR_CPU1_P1_VCC";
40"PVDDCR_CPU1_P1_VCCS";
41"PWRGD_PVDDCR_CPU1_P1_R";
42"PVDDCR_CPU1_P1_EN_R";
43"SVID_PVDDCR_CPU1_P1_SVTI_R";
44"SMB_CLK_PVDDCR_CPU1_P1_R";
45"SVID_PVDDCR_CPU1_P1_SVTO_R";
46"PVDDCR_CPU1_P1_SMB_ALERT_R";
47"SMB_DIO_PVDDCR_CPU1_P1_R";
48"NC_PVDDCR_CPU1_P1_IMON8";
49"PVDDIO_P1_TEMP1";
50"PVDDCR_CPU1_P1_OCP_N_R";
51"VSENSE_PVDDIO_P1_VSEN1";
52"PVDDCR_CPU1_P1_RESET_N_R";
53"PVDD18_S5_P1\g";
54"GND\g";
55"PVDDCR_CPU1_P1_VINSEN";
56"PVDD18_S5_P1\g";
57"PWRGD_PVDDIO_P1_R";
58"P12V_STBY\g";
59"PVDDCR_CPU1_P1_SMB_ALERT";
60"PWRGD_PVDDCR_CPU1_P1";
61"FM_PVDDCR_CPU1_P1_EN";
62"SMB_SCM_6_R2_SCL";
63"SMB_SCM_6_R2_SDA";
64"GND\g";
65"PVDDCR_CPU1_P1_VMON";
66"PVDDCR_CPU1_P1_EN1_ADDR_CFG";
67"PVDD18_S5_P1\g";
68"SVID_PVDDCR_CPU1_P1_SVC_R";
69"SVID_PVDDCR_CPU1_P1_SVD_R";
70"SVID_PVDDCR_CPU1_P1_SVTO";
71"SVID_PVDDCR_CPU1_P1_SVTI";
72"GND\g";
73"P3V3_STBY\g";
74"PVDDIO_P1_EN_G";
75"PWRGD_PVDDIO_P1";
76"GND\g";
77"PVDDIO_P1_EN_R";
78"PVDDIO_P1_EN";
79"NC_PVDDCR_CPU1_P1_PWM7";
80"PVDDCR_CPU1_P1_TEMP0";
81"PVDDCR_CPU1_P1_OCP_N";
82"PVDDCR_CPU1_P1_RESET_N";
83"PVDDIO_P1_PWM4";
84"PVDDCR_CPU1_P1_PWM2";
85"PVDDCR_CPU1_P1_PWM3";
86"PVDDCR_CPU1_P1_IMON3";
87"PVDDIO_P1_PWM3";
88"PVDDIO_P1_IMON4";
89"NC_PVDDCR_CPU1_P1_IMON7";
90"NC_PVDDCR_CPU1_P1_PWM8";
91"PVDDCR_CPU1_P1_IMON6";
92"PVDDCR_CPU1_P1_IMON5";
93"PVDDCR_CPU1_P1_PWM4";
94"VSENSE_PVDDCR_CPU1_P1_VSEN0";
%"Q_RES"
"1","(-8600,1025)","0","pure_quanta","I219";
;
LOCATION"PR230"
$SEC"1"
CDS_SEC"1"
MATERIAL"CHIP"
TOLERANCE"1%"
VALUE"40.2K"
PACK_TYPE"0402LF"
CDS_LIB"pure_quanta"
WATTAGE"1/16W"
PART_NUMBER"TMP_QCS34022FB15";
"B"
$PN"2"65;
"A"
$PN"1"10;
%"Q_RES"
"1","(-7275,850)","0","pure_quanta","I220";
;
LOCATION"PR251"
$SEC"1"
CDS_SEC"1"
WATTAGE"1/16W"
MATERIAL"CHIP"
TOLERANCE"5%"
VALUE"0"
PART_NUMBER"CS00002JB38"
PACK_TYPE"0402LF"
CDS_LIB"pure_quanta";
"B"
$PN"2"55;
"A"
$PN"1"58;
%"VCC_CORE"
"1","(-7525,925)","0","pure_quanta_power","I221";
;
HDL_POWER"P12V_STBY"
CDS_LIB"pure_quanta_power";
"A"58;
%"VCC_CORE"
"1","(-8450,1375)","0","pure_quanta_power","I222";
;
HDL_POWER"P3V3_STBY"
CDS_LIB"pure_quanta_power";
"A"1;
%"Q_RES"
"1","(-7975,1125)","0","pure_quanta","I223";
;
LOCATION"PR243"
$SEC"1"
CDS_SEC"1"
WATTAGE"1/16W"
MATERIAL"CHIP"
TOLERANCE"5%"
VALUE"0"
PART_NUMBER"CS00002JB38"
PACK_TYPE"0402LF"
CDS_LIB"pure_quanta";
"B"
$PN"2"57;
"A"
$PN"1"75;
%"Q_RES"
"1","(-7975,1275)","0","pure_quanta","I224";
;
LOCATION"PR242"
$SEC"1"
CDS_SEC"1"
WATTAGE"1/16W"
MATERIAL"CHIP"
TOLERANCE"1%"
VALUE"1K"
PART_NUMBER"TMP_QCS21002FB24"
PACK_TYPE"0402LF"
CDS_LIB"pure_quanta";
"B"
$PN"2"57;
"A"
$PN"1"1;
%"UNIVERSAL_GND"
"1","(-7800,550)","0","pure_quanta_power","I226";
;
CDS_LIB"pure_quanta_power"
HDL_POWER"GND";
"A"64;
%"Q_RES"
"2","(-8250,850)","0","pure_quanta","I227";
;
LOCATION"PR231"
$SEC"1"
CDS_SEC"1"
WATTAGE"1/16W"
MATERIAL"CHIP"
TOLERANCE"1%"
VALUE"10K"
PACK_TYPE"0402LF"
PART_NUMBER"TMP_QCS31002FB26"
CDS_LIB"pure_quanta";
"A"
$PN"1"65;
"B"
$PN"2"64;
%"Q_CAP"
"1","(-7800,875)","0","pure_quanta","I228";
;
LOCATION"PC357"
$SEC"1"
CDS_SEC"1"
MATERIAL"X7R"
TOLERANCE"10%"
VALUE"0.1UF"
VOLTAGE"25V"
PACK_TYPE"0402"
PART_NUMBER"CH4104K1B00"
CDS_LIB"pure_quanta";
"B"
$PN"2"64;
"A"
$PN"1"65;
%"Q_CAP"
"2","(-7175,1275)","0","pure_quanta","I230";
;
LOCATION"PC362"
$SEC"1"
CDS_SEC"1"
MATERIAL"EMPTY"
TOLERANCE"5%"
VALUE"1000PF"
PART_NUMBER"TMP_QCH21006JB10"
VOLTAGE"50V"
PACK_TYPE"0402"
CDS_LIB"pure_quanta";
"A"
$PN"1"57;
"B"
$PN"2"4;
%"Q_CAP"
"1","(-7225,3100)","0","pure_quanta","I245";
;
LOCATION"PC361"
$SEC"1"
CDS_SEC"1"
MATERIAL"X7R"
TOLERANCE"10%"
VALUE"3300PF"
PART_NUMBER"TMP_QCH2336K1B12"
VOLTAGE"50V"
PACK_TYPE"0402"
CDS_LIB"pure_quanta";
"B"
$PN"2"21;
"A"
$PN"1"51;
%"Q_RES"
"1","(-7675,3275)","0","pure_quanta","I246";
;
LOCATION"PR246"
$SEC"1"
CDS_SEC"1"
WATTAGE"1/16W"
MATERIAL"CHIP"
TOLERANCE"5%"
VALUE"10"
PART_NUMBER"TMP_QCS01002JB22"
PACK_TYPE"0402LF"
CDS_LIB"pure_quanta";
"B"
$PN"2"51;
"A"
$PN"1"22;
%"Q_CAP"
"1","(-7275,4200)","0","pure_quanta","I247";
;
LOCATION"PC358"
$SEC"1"
CDS_SEC"1"
PART_NUMBER"TMP_QCH2336K1B12"
MATERIAL"X7R"
TOLERANCE"10%"
VALUE"3300PF"
VOLTAGE"50V"
PACK_TYPE"0402"
CDS_LIB"pure_quanta";
"B"
$PN"2"24;
"A"
$PN"1"94;
%"Q_RES"
"1","(-7725,4375)","0","pure_quanta","I271";
;
LOCATION"PR245"
$SEC"1"
CDS_SEC"1"
PACK_TYPE"0402LF"
WATTAGE"1/16W"
MATERIAL"CHIP"
TOLERANCE"5%"
VALUE"10"
PART_NUMBER"TMP_QCS01002JB22"
CDS_LIB"pure_quanta";
"B"
$PN"2"94;
"A"
$PN"1"25;
%"Q_RES"
"1","(-7375,5225)","0","pure_quanta","I273";
;
LOCATION"PR248"
$SEC"1"
CDS_SEC"1"
WATTAGE"1/16W"
MATERIAL"CHIP"
TOLERANCE"5%"
VALUE"0"
PART_NUMBER"CS00002JB38"
PACK_TYPE"0402LF"
CDS_LIB"pure_quanta";
"B"
$PN"2"44;
"A"
$PN"1"62;
%"Q_CAP"
"2","(-7250,6100)","0","pure_quanta","I274";
;
LOCATION"PC359"
$SEC"1"
CDS_SEC"1"
MATERIAL"X7R"
TOLERANCE"5%"
VALUE"1000PF"
PART_NUMBER"TMP_QCH21006JB10"
VOLTAGE"50V"
PACK_TYPE"0402"
CDS_LIB"pure_quanta";
"A"
$PN"1"42;
"B"
$PN"2"6;
%"Q_RES"
"1","(-8075,6225)","0","pure_quanta","I275";
;
LOCATION"PR235"
$SEC"1"
CDS_SEC"1"
WATTAGE"1/16W"
MATERIAL"CHIP"
TOLERANCE"5%"
VALUE"0"
PART_NUMBER"CS00002JB38"
PACK_TYPE"0402LF"
CDS_LIB"pure_quanta";
"B"
$PN"2"42;
"A"
$PN"1"61;
%"VCC_CORE"
"1","(-8500,6625)","0","pure_quanta_power","I276";
;
HDL_POWER"P3V3_STBY"
CDS_LIB"pure_quanta_power";
"A"2;
%"Q_RES"
"1","(-8075,6375)","0","pure_quanta","I277";
;
LOCATION"PR234"
$SEC"1"
CDS_SEC"1"
WATTAGE"1/16W"
MATERIAL"CHIP"
TOLERANCE"5%"
VALUE"0"
PART_NUMBER"CS00002JB38"
PACK_TYPE"0402LF"
CDS_LIB"pure_quanta";
"B"
$PN"2"41;
"A"
$PN"1"60;
%"Q_RES"
"1","(-8075,6525)","0","pure_quanta","I278";
;
LOCATION"PR233"
$SEC"1"
CDS_SEC"1"
WATTAGE"1/16W"
MATERIAL"CHIP"
TOLERANCE"1%"
VALUE"1K"
PART_NUMBER"TMP_QCS21002FB24"
PACK_TYPE"0402LF"
CDS_LIB"pure_quanta";
"B"
$PN"2"41;
"A"
$PN"1"2;
%"Q_CAP"
"2","(-7225,6525)","0","pure_quanta","I279";
;
LOCATION"PC360"
$SEC"1"
CDS_SEC"1"
MATERIAL"EMPTY"
TOLERANCE"5%"
VALUE"1000PF"
PART_NUMBER"TMP_QCH21006JB10"
VOLTAGE"50V"
PACK_TYPE"0402"
CDS_LIB"pure_quanta";
"A"
$PN"1"41;
"B"
$PN"2"7;
%"UNIVERSAL_GND"
"1","(-6650,450)","0","pure_quanta_power","I280";
;
CDS_LIB"pure_quanta_power"
HDL_POWER"GND";
"A"3;
%"Q_CAP"
"1","(-6650,675)","0","pure_quanta","I281";
;
LOCATION"PC364"
$SEC"1"
CDS_SEC"1"
MATERIAL"X7R"
TOLERANCE"10%"
VALUE"0.1UF"
PART_NUMBER"CH4104K1B00"
VOLTAGE"25V"
PACK_TYPE"0402"
CDS_LIB"pure_quanta";
"B"
$PN"2"3;
"A"
$PN"1"55;
%"UNIVERSAL_GND"
"1","(-6450,700)","0","pure_quanta_power","I282";
;
CDS_LIB"pure_quanta_power"
HDL_POWER"GND";
"A"54;
%"UNIVERSAL_GND"
"1","(-6475,1275)","1","pure_quanta_power","I284";
;
CDS_LIB"pure_quanta_power"
HDL_POWER"GND";
"A"4;
%"UNIVERSAL_GND"
"1","(-4350,750)","0","pure_quanta_power","I285";
;
CDS_LIB"pure_quanta_power"
HDL_POWER"GND";
"A"5;
%"Q_CAP"
"1","(-4350,1000)","0","pure_quanta","I286";
;
LOCATION"PC368"
$SEC"1"
CDS_SEC"1"
VOLTAGE"50V"
MATERIAL"X7R"
TOLERANCE"10%"
VALUE"470PF"
PART_NUMBER"TMP_QCH14706KB18"
PACK_TYPE"0402"
CDS_LIB"pure_quanta";
"B"
$PN"2"5;
"A"
$PN"1"80;
%"UNIVERSAL_GND"
"1","(-6525,6100)","1","pure_quanta_power","I311";
;
CDS_LIB"pure_quanta_power"
HDL_POWER"GND";
"A"6;
%"UNIVERSAL_GND"
"1","(-6525,6525)","1","pure_quanta_power","I312";
;
CDS_LIB"pure_quanta_power"
HDL_POWER"GND";
"A"7;
%"Q_CAP"
"1","(-4350,5725)","0","pure_quanta","I319";
;
LOCATION"PC366"
$SEC"1"
CDS_SEC"1"
MATERIAL"X6S"
TOLERANCE"20%"
VALUE"10UF"
PART_NUMBER"CH6101MEB01"
VOLTAGE"6.3V"
PACK_TYPE"C0402"
CDS_LIB"pure_quanta";
"B"
$PN"2"13;
"A"
$PN"1"40;
%"Q_CAP"
"1","(-4350,6200)","0","pure_quanta","I322";
;
LOCATION"PC365"
$SEC"1"
CDS_SEC"1"
MATERIAL"X6S"
TOLERANCE"10%"
VALUE"1UF"
PART_NUMBER"CH5103KEB01"
VOLTAGE"16V"
PACK_TYPE"C0402"
CDS_LIB"pure_quanta";
"B"
$PN"2"12;
"A"
$PN"1"39;
%"Q_RES"
"1","(-3900,6375)","0","pure_quanta","I325";
;
LOCATION"PR253"
$SEC"1"
CDS_SEC"1"
WATTAGE"1/16W"
MATERIAL"CHIP"
TOLERANCE"1%"
VALUE"1"
PART_NUMBER"CS-1002FB23"
PACK_TYPE"0402LF"
CDS_LIB"pure_quanta";
"B"
$PN"2"27;
"A"
$PN"1"39;
%"VCC_CORE"
"1","(-3375,6500)","0","pure_quanta_power","I326";
;
HDL_POWER"P3V3_STBY"
CDS_LIB"pure_quanta_power";
"A"27;
%"RAA229620GNPHA0"
"1","(-5675,3625)","0","pure_quanta","I339";
;
LOCATION"PU34"
$SEC"1"
CDS_SEC"1"
VALUE"RAA229620GNP#HA0"
PART_NUMBER"AR0T6GPV005"
MATERIAL"IC"
PART_TYPE"SMLF"
CDS_LIB"pure_quanta"
CDS_LMAN_SYM_OUTLINE"-550,2850,500,-2850"
NEEDS_NO_SIZE"TRUE";
"CS10"
$PN"28"33;
"PWM10"
$PN"11"84;
"CS9"
$PN"29"86;
"PWM9"
$PN"10"85;
"CS8"
$PN"30"32;
"PWM8"
$PN"9"93;
"CS7"
$PN"31"92;
"PWM7"
$PN"8"31;
"CS0"
$PN"38"36;
"PWM0"
$PN"1"37;
"TEMP1"
$PN"43"49;
"EN1||ADDR_CFG"
$PN"42"66;
"TH_GND"
$PN"TH"54;
"OCP_L \B"
$PN"41"50;
"CS2"
$PN"36"38;
"PWM2"
$PN"3"87;
"CS3"
$PN"35"88;
"PWM3"
$PN"4"83;
"PWM11"
$PN"12"35;
"CS1"
$PN"37"29;
"RGND1"
$PN"39"21;
"VSEN1"
$PN"40"51;
"VDDIO"
$PN"19"56;
"TEMP0"
$PN"44"80;
"VINSEN"
$PN"46"55;
"VMON||IINSEN"
$PN"45"65;
"VCCS"
$PN"48"40;
"PWM6"
$PN"7"30;
"PG0"
$PN"16"41;
"PWM1"
$PN"2"28;
"VSEN0"
$PN"25"94;
"PWM5"
$PN"6"79;
"PWM4"
$PN"5"90;
"PMSDA"
$PN"13"47;
"RGND0"
$PN"26"24;
"EN0"
$PN"17"42;
"NPMALERT \B"
$PN"15"46;
"SVD"
$PN"21"69;
"PG1"
$PN"20"57;
"CS4"
$PN"34"48;
"CS5"
$PN"33"89;
"RESET_L \B"
$PN"18"52;
"SVTO"
$PN"23"45;
"CS6"
$PN"32"91;
"SVC"
$PN"22"68;
"PMSCL"
$PN"14"44;
"SVTI"
$PN"24"43;
"VCC"
$PN"47"39;
"CS11"
$PN"27"34;
%"Q_RES"
"1","(-8075,5625)","0","pure_quanta","I348";
;
LOCATION"PR238"
$SEC"1"
CDS_SEC"1"
WATTAGE"1/16W"
MATERIAL"CHIP"
TOLERANCE"5%"
VALUE"0"
PART_NUMBER"CS00002JB38"
PACK_TYPE"0402LF"
CDS_LIB"pure_quanta";
"B"
$PN"2"45;
"A"
$PN"1"70;
%"Q_RES"
"1","(-8075,5475)","0","pure_quanta","I351";
;
LOCATION"PR239"
$SEC"1"
CDS_SEC"1"
WATTAGE"1/16W"
MATERIAL"CHIP"
TOLERANCE"5%"
VALUE"0"
PART_NUMBER"CS00002JB38"
PACK_TYPE"0402LF"
CDS_LIB"pure_quanta";
"B"
$PN"2"43;
"A"
$PN"1"71;
%"Q_RES"
"1","(-7375,5075)","0","pure_quanta","I366";
;
LOCATION"PR249"
$SEC"1"
CDS_SEC"1"
WATTAGE"1/16W"
MATERIAL"CHIP"
TOLERANCE"5%"
VALUE"0"
PART_NUMBER"CS00002JB38"
PACK_TYPE"0402LF"
CDS_LIB"pure_quanta";
"B"
$PN"2"47;
"A"
$PN"1"63;
%"Q_RES"
"1","(-7375,4925)","0","pure_quanta","I367";
;
LOCATION"PR250"
$SEC"1"
CDS_SEC"1"
WATTAGE"1/16W"
MATERIAL"CHIP"
TOLERANCE"5%"
VALUE"0"
PART_NUMBER"CS00002JB38"
PACK_TYPE"0402LF"
CDS_LIB"pure_quanta";
"B"
$PN"2"46;
"A"
$PN"1"59;
%"Q_RES"
"1","(-7400,2375)","0","pure_quanta","I372";
;
LOCATION"PR241"
$SEC"1"
CDS_SEC"1"
PART_NUMBER"CS00002JB38"
WATTAGE"1/16W"
MATERIAL"CHIP"
TOLERANCE"5%"
VALUE"0"
PACK_TYPE"0402LF"
CDS_LIB"pure_quanta";
"B"
$PN"2"50;
"A"
$PN"1"81;
%"Q_RES"
"1","(-7425,2675)","0","pure_quanta","I378";
;
LOCATION"PR247"
$SEC"1"
CDS_SEC"1"
WATTAGE"1/16W"
MATERIAL"CHIP"
TOLERANCE"1%"
VALUE"1K"
PART_NUMBER"TMP_QCS21002FB24"
PACK_TYPE"0402LF"
CDS_LIB"pure_quanta";
"B"
$PN"2"52;
"A"
$PN"1"53;
%"Q_RES"
"1","(-7400,2525)","0","pure_quanta","I379";
;
LOCATION"PR240"
$SEC"1"
CDS_SEC"1"
PART_NUMBER"CS00002JB38"
WATTAGE"1/16W"
MATERIAL"CHIP"
TOLERANCE"5%"
VALUE"0"
PACK_TYPE"0402LF"
CDS_LIB"pure_quanta";
"B"
$PN"2"52;
"A"
$PN"1"82;
%"Q_CAP"
"2","(-7025,2000)","0","pure_quanta","I380";
;
LOCATION"PC363"
$SEC"1"
CDS_SEC"1"
MATERIAL"X7R"
TOLERANCE"10%"
VALUE"1UF"
PART_NUMBER"CH5101K1B01"
VOLTAGE"6.3V"
PACK_TYPE"0402"
CDS_LIB"pure_quanta";
"A"
$PN"1"56;
"B"
$PN"2"8;
%"UNIVERSAL_GND"
"1","(-6625,2000)","1","pure_quanta_power","I381";
;
CDS_LIB"pure_quanta_power"
HDL_POWER"GND";
"A"8;
%"VCC_CORE"
"1","(-7575,2075)","0","pure_quanta_power","I382";
;
HDL_POWER"PVDD18_S5_P1"
CDS_LIB"pure_quanta_power";
"A"56;
%"Q_RES"
"1","(-6750,2250)","0","pure_quanta","I385";
;
LOCATION"PR252"
$SEC"1"
CDS_SEC"1"
WATTAGE"1/16W"
MATERIAL"CHIP"
TOLERANCE"1%"
VALUE"1K"
PART_NUMBER"TMP_QCS21002FB24"
PACK_TYPE"0402LF"
CDS_LIB"pure_quanta";
"B"
$PN"2"50;
"A"
$PN"1"56;
%"VCC_CORE"
"1","(-9200,2650)","0","pure_quanta_power","I390";
;
HDL_POWER"P3V3_STBY"
CDS_LIB"pure_quanta_power";
"A"73;
%"MOSFET_N"
"1","(-9250,1825)","0","pure_quanta","I391";
;
LOCATION"PQ16"
$SEC"1"
CDS_SEC"1"
MATERIAL"IC"
VALUE"BSS138K"
PART_NUMBER"BAM138K0000"
CDS_LIB"pure_quanta"
CDS_LMAN_SYM_OUTLINE"-50,50,100,-150"
MANUF_PN"BSS138K"
PACK_TYPE"SMLF";
"GATE"
$PN"G"77;
"SOURCE"
$PN"S"76;
"DRAIN"
$PN"D"74;
%"Q_RES"
"2","(-9200,2400)","0","pure_quanta","I392";
;
LOCATION"PR232"
$SEC"1"
CDS_SEC"1"
WATTAGE"1/16W"
MATERIAL"CHIP"
TOLERANCE"1%"
VALUE"1K"
PACK_TYPE"0402LF"
CDS_LIB"pure_quanta"
PART_NUMBER"TMP_QCS21002FB24";
"A"
$PN"1"73;
"B"
$PN"2"74;
%"UNIVERSAL_GND"
"1","(-9200,1425)","0","pure_quanta_power","I393";
;
CDS_LIB"pure_quanta_power"
HDL_POWER"GND";
"A"76;
%"Q_RES"
"2","(-8500,1675)","0","pure_quanta","I394";
;
LOCATION"PR244"
$SEC"1"
CDS_SEC"1"
PART_NUMBER"TMP_QCS29532FB10"
PACK_TYPE"0402LF "
WATTAGE"1/16W "
MATERIAL"CHIP"
TOLERANCE"1%"
VALUE"9.53K"
CDS_LIB"pure_quanta";
"A"
$PN"1"66;
"B"
$PN"2"76;
%"Q_RES"
"1","(-9900,1725)","0","pure_quanta","I395";
;
LOCATION"PR224"
$SEC"1"
CDS_SEC"1"
VALUE"0"
PART_NUMBER"CS00002JB38"
WATTAGE"1/16W"
MATERIAL"CHIP"
TOLERANCE"5%"
PACK_TYPE"0402LF"
CDS_LIB"pure_quanta";
"B"
$PN"2"77;
"A"
$PN"1"78;
%"Q_CAP"
"1","(-9700,1550)","0","pure_quanta","I397";
;
LOCATION"PC356"
$SEC"1"
CDS_SEC"1"
MATERIAL"X7R"
TOLERANCE"5%"
VALUE"1000PF"
PART_NUMBER"TMP_QCH21006JB10"
VOLTAGE"50V"
PACK_TYPE"0402"
CDS_LIB"pure_quanta";
"B"
$PN"2"9;
"A"
$PN"1"77;
%"UNIVERSAL_GND"
"1","(-9700,1300)","0","pure_quanta_power","I398";
;
CDS_LIB"pure_quanta_power"
HDL_POWER"GND";
"A"9;
%"VCC_CORE"
"1","(-8925,1075)","0","pure_quanta_power","I399";
;
HDL_POWER"P5V_STBY"
CDS_LIB"pure_quanta_power";
"A"10;
%"Q_CAP"
"1","(-4350,1575)","0","pure_quanta","I400";
;
LOCATION"PC367"
$SEC"1"
CDS_SEC"1"
MATERIAL"X7R"
TOLERANCE"10%"
VALUE"470PF"
PART_NUMBER"TMP_QCH14706KB18"
VOLTAGE"50V"
PACK_TYPE"0402"
CDS_LIB"pure_quanta";
"B"
$PN"2"11;
"A"
$PN"1"49;
%"UNIVERSAL_GND"
"1","(-4350,1325)","0","pure_quanta_power","I401";
;
CDS_LIB"pure_quanta_power"
HDL_POWER"GND";
"A"11;
%"Q_RES"
"2","(-9400,6250)","0","pure_quanta","I408";
;
LOCATION"PR225"
$SEC"1"
CDS_SEC"1"
WATTAGE"1/16W"
MATERIAL"EMPTY"
TOLERANCE"1%"
VALUE"1K"
PART_NUMBER"TMP_QCS21002FB24"
PACK_TYPE"0402LF"
CDS_LIB"pure_quanta";
"A"
$PN"1"67;
"B"
$PN"2"68;
%"Q_RES"
"2","(-10150,6250)","0","pure_quanta","I409";
;
LOCATION"PR218"
$SEC"1"
CDS_SEC"1"
WATTAGE"1/16W"
MATERIAL"EMPTY"
TOLERANCE"1%"
VALUE"1K"
PACK_TYPE"0402LF"
CDS_LIB"pure_quanta"
PART_NUMBER"TMP_QCS21002FB24";
"A"
$PN"1"67;
"B"
$PN"2"71;
%"Q_RES"
"2","(-9775,6250)","0","pure_quanta","I410";
;
LOCATION"PR220"
$SEC"1"
CDS_SEC"1"
WATTAGE"1/16W"
MATERIAL"EMPTY"
TOLERANCE"1%"
VALUE"1K"
PACK_TYPE"0402LF"
CDS_LIB"pure_quanta"
PART_NUMBER"TMP_QCS21002FB24";
"A"
$PN"1"67;
"B"
$PN"2"70;
%"Q_RES"
"2","(-9600,6250)","0","pure_quanta","I411";
;
LOCATION"PR222"
$SEC"1"
CDS_SEC"1"
WATTAGE"1/16W"
MATERIAL"EMPTY"
TOLERANCE"1%"
VALUE"1K"
PACK_TYPE"0402LF"
CDS_LIB"pure_quanta"
PART_NUMBER"TMP_QCS21002FB24";
"A"
$PN"1"67;
"B"
$PN"2"69;
%"Q_RES"
"2","(-10025,5275)","0","pure_quanta","I414";
;
LOCATION"PR219"
$SEC"1"
CDS_SEC"1"
MATERIAL"EMPTY"
TOLERANCE"1%"
VALUE"1K"
PACK_TYPE"0402LF"
WATTAGE"1/16W"
CDS_LIB"pure_quanta"
PART_NUMBER"TMP_QCS21002FB24";
"A"
$PN"1"70;
"B"
$PN"2"72;
%"Q_RES"
"2","(-10200,5275)","0","pure_quanta","I415";
;
LOCATION"PR217"
$SEC"1"
CDS_SEC"1"
WATTAGE"1/16W"
MATERIAL"CHIP"
TOLERANCE"5%"
VALUE"0"
PACK_TYPE"0402LF"
CDS_LIB"pure_quanta"
PART_NUMBER"CS00002JB38";
"A"
$PN"1"71;
"B"
$PN"2"72;
%"UNIVERSAL_GND"
"1","(-10200,4825)","0","pure_quanta_power","I416";
;
CDS_LIB"pure_quanta_power"
HDL_POWER"GND";
"A"72;
%"VCC_CORE"
"1","(-10150,6600)","0","pure_quanta_power","I417";
;
HDL_POWER"PVDD18_S5_P1"
CDS_LIB"pure_quanta_power";
"A"67;
%"UNIVERSAL_GND"
"1","(-4350,6000)","0","pure_quanta_power","I418";
;
CDS_LIB"pure_quanta_power"
HDL_POWER"GND";
"A"12;
%"UNIVERSAL_GND"
"1","(-4350,5525)","0","pure_quanta_power","I419";
;
CDS_LIB"pure_quanta_power"
HDL_POWER"GND";
"A"13;
%"VCC_CORE"
"1","(-7875,2800)","0","pure_quanta_power","I423";
;
HDL_POWER"PVDD18_S5_P1"
CDS_LIB"pure_quanta_power";
"A"53;
%"MOSFET_PCH_GDS_ESD_PROTECTED"
"1","(-8525,2200)","6","pure_quanta","I424";
;
LOCATION"PQ12"
$SEC"1"
CDS_SEC"1"
MATERIAL"IC"
VALUE"PJA3415AE"
PART_NUMBER"BAM34150008"
CDS_LMAN_SYM_OUTLINE"-125,150,125,-150"
CDS_LIB"pure_quanta"
NEEDS_NO_SIZE"TRUE"
PART_TYPE"SMLF";
"S"
$PN"S"73;
"G"
$PN"G"74;
"D"
$PN"D"66;
%"UNIVERSAL_GND"
"1","(-4725,5525)","0","pure_quanta_power","I425";
;
CDS_LIB"pure_quanta_power"
HDL_POWER"GND";
"A"14;
%"Q_CAP"
"1","(-4725,5750)","0","pure_quanta","I426";
;
LOCATION"PC93"
$SEC"1"
CDS_SEC"1"
MATERIAL"X7R"
TOLERANCE"10%"
VALUE"0.1UF"
PART_NUMBER"CH4104K1B00"
VOLTAGE"25V"
PACK_TYPE"0402"
CDS_LIB"pure_quanta";
"B"
$PN"2"14;
"A"
$PN"1"40;
%"UNIVERSAL_GND"
"1","(-4725,6000)","0","pure_quanta_power","I427";
;
CDS_LIB"pure_quanta_power"
HDL_POWER"GND";
"A"15;
%"Q_CAP"
"1","(-4725,6225)","0","pure_quanta","I428";
;
LOCATION"PC29"
$SEC"1"
CDS_SEC"1"
MATERIAL"X7R"
TOLERANCE"10%"
VALUE"0.1UF"
PART_NUMBER"CH4104K1B00"
VOLTAGE"25V"
PACK_TYPE"0402"
CDS_LIB"pure_quanta";
"B"
$PN"2"15;
"A"
$PN"1"39;
%"Q_CAP"
"1","(-9450,5275)","0","pure_quanta","I499";
;
LOCATION"PC310"
$SEC"1"
CDS_SEC"1"
MATERIAL"EMPTY"
TOLERANCE"5%"
VALUE"10PF"
PART_NUMBER"CH01006JB08"
VOLTAGE"50V"
PACK_TYPE"0402"
CDS_LIB"pure_quanta";
"B"
$PN"2"72;
"A"
$PN"1"68;
%"Q_CAP"
"1","(-9650,5275)","0","pure_quanta","I500";
;
LOCATION"PC309"
$SEC"1"
CDS_SEC"1"
MATERIAL"EMPTY"
TOLERANCE"5%"
VALUE"10PF"
VOLTAGE"50V"
PACK_TYPE"0402"
CDS_LIB"pure_quanta"
PART_NUMBER"CH01006JB08";
"B"
$PN"2"72;
"A"
$PN"1"69;
%"Q_CAP"
"1","(-9850,5250)","0","pure_quanta","I501";
;
LOCATION"PC308"
$SEC"1"
CDS_SEC"1"
MATERIAL"EMPTY"
TOLERANCE"5%"
VALUE"10PF"
VOLTAGE"50V"
PACK_TYPE"0402"
CDS_LIB"pure_quanta"
PART_NUMBER"CH01006JB08";
"B"
$PN"2"72;
"A"
$PN"1"70;
%"Q_RES"
"1","(-8550,4525)","0","pure_quanta","I502";
;
LOCATION"PR228"
$SEC"1"
CDS_SEC"1"
WATTAGE"1/16W"
MATERIAL"CHIP"
PART_NUMBER"CS04992FB31"
PACK_TYPE"0402LF"
VALUE"49.9"
TOLERANCE"1%"
CDS_LIB"pure_quanta";
"B"
$PN"2"26;
"A"
$PN"1"25;
%"VCC_CORE"
"1","(-7875,4675)","0","pure_quanta_power","I503";
;
HDL_POWER"PVDDCR_CPU1_P1"
CDS_LIB"pure_quanta_power";
"A"26;
%"Q_RES"
"1","(-8600,3850)","0","pure_quanta","I504";
;
LOCATION"PR226"
$SEC"1"
CDS_SEC"1"
WATTAGE"1/16W"
MATERIAL"CHIP"
PART_NUMBER"CS04992FB31"
PACK_TYPE"0402LF"
VALUE"49.9"
TOLERANCE"1%"
CDS_LIB"pure_quanta";
"B"
$PN"2"16;
"A"
$PN"1"24;
%"UNIVERSAL_GND"
"1","(-8075,3750)","0","pure_quanta_power","I505";
;
CDS_LIB"pure_quanta_power"
HDL_POWER"GND";
"A"16;
%"Q_RES"
"1","(-8600,3425)","0","pure_quanta","I506";
;
LOCATION"PR227"
$SEC"1"
CDS_SEC"1"
WATTAGE"1/16W"
MATERIAL"CHIP"
PART_NUMBER"CS04992FB31"
PACK_TYPE"0402LF"
VALUE"49.9"
TOLERANCE"1%"
CDS_LIB"pure_quanta";
"B"
$PN"2"23;
"A"
$PN"1"22;
%"VCC_CORE"
"1","(-8075,3575)","0","pure_quanta_power","I507";
;
HDL_POWER"PVDDIO_P1"
CDS_LIB"pure_quanta_power";
"A"23;
%"Q_RES"
"1","(-8625,2750)","0","pure_quanta","I508";
;
LOCATION"PR460"
$SEC"1"
CDS_SEC"1"
WATTAGE"1/16W"
MATERIAL"CHIP"
PART_NUMBER"CS04992FB31"
PACK_TYPE"0402LF"
VALUE"49.9"
TOLERANCE"1%"
CDS_LIB"pure_quanta";
"B"
$PN"2"17;
"A"
$PN"1"21;
%"UNIVERSAL_GND"
"1","(-8100,2650)","0","pure_quanta_power","I509";
;
CDS_LIB"pure_quanta_power"
HDL_POWER"GND";
"A"17;
%"UNIVERSAL_GND"
"1","(-3825,3400)","0","pure_quanta_power","I540";
;
CDS_LIB"pure_quanta_power"
HDL_POWER"GND";
"A"18;
%"Q_RES"
"1","(-4275,3475)","0","pure_quanta","I541";
;
LOCATION"PR533"
$SEC"1"
CDS_SEC"1"
PART_NUMBER"CS00002JB38"
PACK_TYPE"0402LF"
TOLERANCE"5%"
WATTAGE"1/16W"
MATERIAL"CHIP"
VALUE"0"
CDS_LIB"pure_quanta";
"B"
$PN"2"18;
"A"
$PN"1"89;
%"UNIVERSAL_GND"
"1","(-3825,3100)","0","pure_quanta_power","I542";
;
CDS_LIB"pure_quanta_power"
HDL_POWER"GND";
"A"19;
%"Q_RES"
"1","(-4275,3175)","0","pure_quanta","I543";
;
LOCATION"PR12"
$SEC"1"
CDS_SEC"1"
WATTAGE"1/16W"
MATERIAL"CHIP"
TOLERANCE"5%"
VALUE"0"
PART_NUMBER"CS00002JB38"
PACK_TYPE"0402LF"
CDS_LIB"pure_quanta";
"B"
$PN"2"19;
"A"
$PN"1"48;
%"UNIVERSAL_GND"
"1","(-7000,450)","0","pure_quanta_power","I544";
;
CDS_LIB"pure_quanta_power"
HDL_POWER"GND";
"A"20;
%"Q_RES"
"2","(-7000,650)","0","pure_quanta","I545";
;
LOCATION"PR603"
$SEC"1"
CDS_SEC"1"
WATTAGE"1/16W"
MATERIAL"EMPTY"
TOLERANCE"1%"
VALUE"4.99K"
PART_NUMBER"CS24992FB07"
PACK_TYPE"0402LF"
CDS_LIB"pure_quanta";
"A"
$PN"1"55;
"B"
$PN"2"20;
END.
